(kicad_pcb
	(version 20241229)
	(generator "pcbnew")
	(generator_version "9.0")
	(general
		(thickness 1.711)
		(legacy_teardrops no)
	)
	(paper "A4")
	(title_block
		(title "Antmicro Baseboard for Jetson AGX Thor")
		(date "2026-02-18")
		(rev "1.1.0")
		(company "Antmicro Ltd")
		(comment 1 "www.antmicro.com")
		(comment 9 "footprints 1050-1054 of 1170")
	)
	(layers
		(0 "F.Cu" signal)
		(4 "In1.Cu" signal)
		(6 "In2.Cu" signal)
		(8 "In3.Cu" signal)
		(10 "In4.Cu" jumper)
		(12 "In5.Cu" signal)
		(14 "In6.Cu" signal)
		(16 "In7.Cu" signal)
		(18 "In8.Cu" signal)
		(2 "B.Cu" signal)
		(9 "F.Adhes" user "F.Adhesive")
		(11 "B.Adhes" user "B.Adhesive")
		(13 "F.Paste" user)
		(15 "B.Paste" user)
		(5 "F.SilkS" user "F.Silkscreen")
		(7 "B.SilkS" user "B.Silkscreen")
		(1 "F.Mask" user)
		(3 "B.Mask" user)
		(17 "Dwgs.User" user "User.Drawings")
		(19 "Cmts.User" user "User.Comments")
		(21 "Eco1.User" user "User.Eco1")
		(23 "Eco2.User" user "User.Eco2")
		(25 "Edge.Cuts" user)
		(27 "Margin" user)
		(31 "F.CrtYd" user "F.Courtyard")
		(29 "B.CrtYd" user "B.Courtyard")
		(35 "F.Fab" user)
		(33 "B.Fab" user)
	)
	(footprint "antmicro-footprints:C_0603_1608Metric_EIA"
		(layer "B.Cu")
		(at 120.64 69.44 180)
		(descr "Capacitor SMD 0603, IPC-7351 Density Level A")
		(tags "Capacitor 0603")
		(property "Reference" "C24"
			(at -1.16 0.84 0)
			(layer "B.SilkS")
			(effects
				(font
					(size 0.7 0.7)
					(thickness 0.15)
				)
				(justify left bottom mirror)
			)
		)
		(property "Value" "C_22u_16V_0603"
			(at -1.42757 -1.770288 0)
			(layer "B.Fab")
			(effects
				(font
					(size 0.7 0.7)
					(thickness 0.15)
				)
				(justify left bottom mirror)
			)
		)
		(property "Datasheet" "https://product.samsungsem.com/mlcc/CL10A226MO7JZN.do"
			(at 0 0 0)
			(layer "B.Fab")
			(hide yes)
			(effects
				(font
					(size 1.27 1.27)
					(thickness 0.15)
				)
				(justify mirror)
			)
		)
		(property "Description" "SMD Multilayer Ceramic Capacitor"
			(at 0 0 0)
			(layer "B.Fab")
			(hide yes)
			(effects
				(font
					(size 1.27 1.27)
					(thickness 0.15)
				)
				(justify mirror)
			)
		)
		(property "MPN" "CL10A226MO7JZNC"
			(at 0 0 180)
			(unlocked yes)
			(layer "B.Fab")
			(hide yes)
			(effects
				(font
					(size 1 1)
					(thickness 0.15)
				)
				(justify mirror)
			)
		)
		(property "Manufacturer" "Samsung Electro-Mechanics"
			(at 0 0 180)
			(unlocked yes)
			(layer "B.Fab")
			(hide yes)
			(effects
				(font
					(size 1 1)
					(thickness 0.15)
				)
				(justify mirror)
			)
		)
		(property "License" "Apache-2.0"
			(at 0 0 180)
			(unlocked yes)
			(layer "B.Fab")
			(hide yes)
			(effects
				(font
					(size 1 1)
					(thickness 0.15)
				)
				(justify mirror)
			)
		)
		(property "Author" "Antmicro"
			(at 0 0 180)
			(unlocked yes)
			(layer "B.Fab")
			(hide yes)
			(effects
				(font
					(size 1 1)
					(thickness 0.15)
				)
				(justify mirror)
			)
		)
		(property "Val" "22u"
			(at 0 0 180)
			(unlocked yes)
			(layer "B.Fab")
			(hide yes)
			(effects
				(font
					(size 1 1)
					(thickness 0.15)
				)
				(justify mirror)
			)
		)
		(property "Voltage" "16V"
			(at 0 0 180)
			(unlocked yes)
			(layer "B.Fab")
			(hide yes)
			(effects
				(font
					(size 1 1)
					(thickness 0.15)
				)
				(justify mirror)
			)
		)
		(property "Dielectric" "X7R"
			(at 0 0 180)
			(unlocked yes)
			(layer "B.Fab")
			(hide yes)
			(effects
				(font
					(size 1 1)
					(thickness 0.15)
				)
				(justify mirror)
			)
		)
		(property "Public" "False"
			(at 0 0 180)
			(unlocked yes)
			(layer "B.Fab")
			(hide yes)
			(effects
				(font
					(size 1 1)
					(thickness 0.15)
				)
				(justify mirror)
			)
		)
		(sheetname "/SoM_Power/")
		(sheetfile "som_power.kicad_sch")
		(attr smd)
		(fp_line
			(start -0.15 0.55)
			(end 0.15 0.55)
			(stroke
				(width 0.15)
				(type solid)
			)
			(layer "B.SilkS")
		)
		(fp_line
			(start -0.15 -0.55)
			(end 0.15 -0.55)
			(stroke
				(width 0.15)
				(type solid)
			)
			(layer "B.SilkS")
		)
		(fp_rect
			(start -1.25 0.65)
			(end 1.25 -0.65)
			(stroke
				(width 0.05)
				(type solid)
			)
			(fill no)
			(layer "B.CrtYd")
		)
		(fp_rect
			(start -0.8 0.45)
			(end 0.8 -0.45)
			(stroke
				(width 0.15)
				(type solid)
			)
			(fill no)
			(layer "B.Fab")
		)
		(fp_text user "License: Apache-2.0"
			(at -1.682 -5.895 0)
			(layer "B.Fab")
			(effects
				(font
					(size 0.7 0.7)
					(thickness 0.15)
				)
				(justify left bottom mirror)
			)
		)
		(fp_text user "${REFERENCE}"
			(at -1.682 -3.895 0)
			(layer "B.Fab")
			(effects
				(font
					(size 0.7 0.7)
					(thickness 0.15)
				)
				(justify left bottom mirror)
			)
		)
		(fp_text user "Author: Antmicro"
			(at -1.682 -4.894 0)
			(layer "B.Fab")
			(effects
				(font
					(size 0.7 0.7)
					(thickness 0.15)
				)
				(justify left bottom mirror)
			)
		)
		(pad "1" smd roundrect
			(at -0.7 0 180)
			(size 0.8 1.1)
			(layers "B.Cu" "B.Mask" "B.Paste")
			(roundrect_rratio 0.2)
			(net 1 "GND")
			(pintype "passive")
		)
		(pad "2" smd roundrect
			(at 0.7 0 180)
			(size 0.8 1.1)
			(layers "B.Cu" "B.Mask" "B.Paste")
			(roundrect_rratio 0.2)
			(net 213 "+5V_SOM")
			(pintype "passive")
		)
	)
	(footprint "antmicro-footprints:TP_SMD_0.75mm"
		(layer "B.Cu")
		(at 233.5 103.3 180)
		(property "Reference" "TP47"
			(at 0 0.6 0)
			(layer "B.SilkS")
			(effects
				(font
					(size 0.7 0.7)
					(thickness 0.15)
				)
				(justify left bottom mirror)
			)
		)
		(property "Value" "TP_0.75mm_SMD"
			(at 0 -1.2 0)
			(layer "B.Fab")
			(effects
				(font
					(size 0.7 0.7)
					(thickness 0.15)
				)
				(justify left bottom mirror)
			)
		)
		(property "Description" "SMT test point"
			(at 0 0 0)
			(layer "B.Fab")
			(hide yes)
			(effects
				(font
					(size 1.27 1.27)
					(thickness 0.15)
				)
				(justify mirror)
			)
		)
		(property "MPN" ""
			(at 0 0 0)
			(unlocked yes)
			(layer "B.Fab")
			(hide yes)
			(effects
				(font
					(size 1 1)
					(thickness 0.15)
				)
				(justify mirror)
			)
		)
		(property "Manufacturer" ""
			(at 0 0 0)
			(unlocked yes)
			(layer "B.Fab")
			(hide yes)
			(effects
				(font
					(size 1 1)
					(thickness 0.15)
				)
				(justify mirror)
			)
		)
		(property "Author" "Antmicro"
			(at 0 0 0)
			(unlocked yes)
			(layer "B.Fab")
			(hide yes)
			(effects
				(font
					(size 1 1)
					(thickness 0.15)
				)
				(justify mirror)
			)
		)
		(property "License" "Apache-2.0"
			(at 0 0 0)
			(unlocked yes)
			(layer "B.Fab")
			(hide yes)
			(effects
				(font
					(size 1 1)
					(thickness 0.15)
				)
				(justify mirror)
			)
		)
		(sheetname "/Recovery USB/")
		(sheetfile "recovery_usb.kicad_sch")
		(attr exclude_from_pos_files exclude_from_bom)
		(fp_circle
			(center 0 0)
			(end 0.475 0)
			(stroke
				(width 0.05)
				(type default)
			)
			(fill no)
			(layer "B.CrtYd")
		)
		(fp_text user "License: Apache-2.0"
			(at -0.4 -5.101 0)
			(layer "B.Fab")
			(effects
				(font
					(size 0.7 0.7)
					(thickness 0.15)
				)
				(justify left bottom mirror)
			)
		)
		(fp_text user "Author: Antmicro"
			(at -0.4 -3.901 0)
			(layer "B.Fab")
			(effects
				(font
					(size 0.7 0.7)
					(thickness 0.15)
				)
				(justify left bottom mirror)
			)
		)
		(fp_text user "${REFERENCE}"
			(at -0.4 -2.7 0)
			(layer "B.Fab")
			(effects
				(font
					(size 0.7 0.7)
					(thickness 0.15)
				)
				(justify left bottom mirror)
			)
		)
		(pad "1" smd circle
			(at 0 0 180)
			(size 0.75 0.75)
			(layers "B.Cu" "B.Mask")
			(net 287 "/Recovery USB/USBC2_VBUS")
			(pinfunction "1")
			(pintype "passive")
		)
	)
	(footprint "antmicro-footprints:R_0402_1005Metric"
		(layer "B.Cu")
		(at 207.8 80.3 180)
		(descr "Resistor SMD 0402")
		(tags "resistor SMD 0402")
		(property "Reference" "R31"
			(at -3.140532 -0.4 0)
			(layer "B.SilkS")
			(effects
				(font
					(size 0.7 0.7)
					(thickness 0.15)
				)
				(justify left bottom mirror)
			)
		)
		(property "Value" "R_15k_0402"
			(at -1.011843 -1.772047 0)
			(layer "B.Fab")
			(effects
				(font
					(size 0.7 0.7)
					(thickness 0.15)
				)
				(justify left bottom mirror)
			)
		)
		(property "Datasheet" "https://www.bourns.com/docs/product-datasheets/cr.pdf"
			(at 0 0 0)
			(layer "B.Fab")
			(hide yes)
			(effects
				(font
					(size 1.27 1.27)
					(thickness 0.15)
				)
				(justify mirror)
			)
		)
		(property "Description" "SMD Chip Resistor, 15 kohm, ± 1%, 62.5 mW, 0402 [1005 Metric], Thick Film, General Purpose"
			(at 0 0 0)
			(layer "B.Fab")
			(hide yes)
			(effects
				(font
					(size 1.27 1.27)
					(thickness 0.15)
				)
				(justify mirror)
			)
		)
		(property "MPN" "CR0402-FX-1502GLF"
			(at 0 0 0)
			(unlocked yes)
			(layer "B.Fab")
			(hide yes)
			(effects
				(font
					(size 1 1)
					(thickness 0.15)
				)
				(justify mirror)
			)
		)
		(property "Manufacturer" "Bourns"
			(at 0 0 0)
			(unlocked yes)
			(layer "B.Fab")
			(hide yes)
			(effects
				(font
					(size 1 1)
					(thickness 0.15)
				)
				(justify mirror)
			)
		)
		(property "License" "Apache-2.0"
			(at 0 0 0)
			(unlocked yes)
			(layer "B.Fab")
			(hide yes)
			(effects
				(font
					(size 1 1)
					(thickness 0.15)
				)
				(justify mirror)
			)
		)
		(property "Author" "Antmicro"
			(at 0 0 0)
			(unlocked yes)
			(layer "B.Fab")
			(hide yes)
			(effects
				(font
					(size 1 1)
					(thickness 0.15)
				)
				(justify mirror)
			)
		)
		(property "Val" "15k"
			(at 0 0 0)
			(unlocked yes)
			(layer "B.Fab")
			(hide yes)
			(effects
				(font
					(size 1 1)
					(thickness 0.15)
				)
				(justify mirror)
			)
		)
		(property "Tolerance" "1%"
			(at 0 0 0)
			(unlocked yes)
			(layer "B.Fab")
			(hide yes)
			(effects
				(font
					(size 1 1)
					(thickness 0.15)
				)
				(justify mirror)
			)
		)
		(sheetname "/USB Debug, PD/")
		(sheetfile "usb_debug_pd.kicad_sch")
		(attr smd)
		(fp_rect
			(start -0.925 0.47)
			(end 0.925 -0.47)
			(stroke
				(width 0.05)
				(type default)
			)
			(fill no)
			(layer "B.CrtYd")
		)
		(fp_rect
			(start -0.5 0.25)
			(end 0.5 -0.25)
			(stroke
				(width 0.15)
				(type solid)
			)
			(fill no)
			(layer "B.Fab")
		)
		(fp_text user "License: Apache-2.0"
			(at -0.95 -5.169 0)
			(layer "B.Fab")
			(effects
				(font
					(size 0.7 0.7)
					(thickness 0.15)
				)
				(justify left bottom mirror)
			)
		)
		(fp_text user "${REFERENCE}"
			(at -0.95 -3.168 0)
			(layer "B.Fab")
			(effects
				(font
					(size 0.7 0.7)
					(thickness 0.15)
				)
				(justify left bottom mirror)
			)
		)
		(fp_text user "Author: Antmicro"
			(at -0.95 -4.169 0)
			(layer "B.Fab")
			(effects
				(font
					(size 0.7 0.7)
					(thickness 0.15)
				)
				(justify left bottom mirror)
			)
		)
		(pad "1" smd roundrect
			(at -0.48 0 180)
			(size 0.59 0.64)
			(layers "B.Cu" "B.Mask" "B.Paste")
			(roundrect_rratio 0.25)
			(net 1 "GND")
			(pintype "passive")
		)
		(pad "2" smd roundrect
			(at 0.48 0 180)
			(size 0.59 0.64)
			(layers "B.Cu" "B.Mask" "B.Paste")
			(roundrect_rratio 0.25)
			(net 934 "/USB Debug, PD/PDC_ADCIN1")
			(pintype "passive")
		)
	)
	(footprint "antmicro-footprints:C_0402_1005Metric"
		(layer "B.Cu")
		(at 225.521 79.335 90)
		(descr "Capacitor SMD 0402")
		(tags "capacitor SMD 0402")
		(property "Reference" "C149"
			(at -3.865 -0.321 90)
			(layer "B.SilkS")
			(effects
				(font
					(size 0.7 0.7)
					(thickness 0.15)
				)
				(justify right top mirror)
			)
		)
		(property "Value" "C_47p_0402"
			(at -1.022927 -2.155213 90)
			(layer "B.Fab")
			(effects
				(font
					(size 0.7 0.7)
					(thickness 0.15)
				)
				(justify right top mirror)
			)
		)
		(property "Datasheet" "https://www.kemet.com/en/us/capacitors/product/C0402C470J5GACTU.html"
			(at 0 0 90)
			(layer "B.Fab")
			(hide yes)
			(effects
				(font
					(size 1.27 1.27)
					(thickness 0.15)
				)
				(justify mirror)
			)
		)
		(property "Description" "SMD Multilayer Ceramic Capacitor, 47 pF, 50 V, 0402 [1005 Metric], ± 5%, C0G / NP0, C Series KEMET"
			(at 0 0 90)
			(layer "B.Fab")
			(hide yes)
			(effects
				(font
					(size 1.27 1.27)
					(thickness 0.15)
				)
				(justify mirror)
			)
		)
		(property "MPN" "C0402C470J5GACTU"
			(at 0 0 270)
			(unlocked yes)
			(layer "B.Fab")
			(hide yes)
			(effects
				(font
					(size 1 1)
					(thickness 0.15)
				)
				(justify mirror)
			)
		)
		(property "Manufacturer" "KEMET"
			(at 0 0 270)
			(unlocked yes)
			(layer "B.Fab")
			(hide yes)
			(effects
				(font
					(size 1 1)
					(thickness 0.15)
				)
				(justify mirror)
			)
		)
		(property "License" "Apache-2.0"
			(at 0 0 270)
			(unlocked yes)
			(layer "B.Fab")
			(hide yes)
			(effects
				(font
					(size 1 1)
					(thickness 0.15)
				)
				(justify mirror)
			)
		)
		(property "Author" "Antmicro"
			(at 0 0 270)
			(unlocked yes)
			(layer "B.Fab")
			(hide yes)
			(effects
				(font
					(size 1 1)
					(thickness 0.15)
				)
				(justify mirror)
			)
		)
		(property "Val" "47p"
			(at 0 0 270)
			(unlocked yes)
			(layer "B.Fab")
			(hide yes)
			(effects
				(font
					(size 1 1)
					(thickness 0.15)
				)
				(justify mirror)
			)
		)
		(property "Voltage" ""
			(at 0 0 270)
			(unlocked yes)
			(layer "B.Fab")
			(hide yes)
			(effects
				(font
					(size 1 1)
					(thickness 0.15)
				)
				(justify mirror)
			)
		)
		(property "Dielectric" "C0G"
			(at 0 0 270)
			(unlocked yes)
			(layer "B.Fab")
			(hide yes)
			(effects
				(font
					(size 1 1)
					(thickness 0.15)
				)
				(justify mirror)
			)
		)
		(sheetname "/USB Debug, PD/")
		(sheetfile "usb_debug_pd.kicad_sch")
		(attr smd)
		(fp_rect
			(start -0.925 0.47)
			(end 0.925 -0.47)
			(stroke
				(width 0.05)
				(type default)
			)
			(fill no)
			(layer "B.CrtYd")
		)
		(fp_line
			(start 0.504 -0.248)
			(end -0.494 -0.248)
			(stroke
				(width 0.15)
				(type solid)
			)
			(layer "B.Fab")
		)
		(fp_line
			(start -0.494 -0.248)
			(end -0.494 0.25)
			(stroke
				(width 0.15)
				(type solid)
			)
			(layer "B.Fab")
		)
		(fp_line
			(start 0.504 0.25)
			(end 0.504 -0.248)
			(stroke
				(width 0.15)
				(type solid)
			)
			(layer "B.Fab")
		)
		(fp_line
			(start -0.494 0.25)
			(end 0.504 0.25)
			(stroke
				(width 0.15)
				(type solid)
			)
			(layer "B.Fab")
		)
		(fp_text user "License: Apache-2.0"
			(at -0.939 -5.799 90)
			(layer "B.Fab")
			(effects
				(font
					(size 0.7 0.7)
					(thickness 0.15)
				)
				(justify right top mirror)
			)
		)
		(fp_text user "Author: Antmicro"
			(at -0.939 -3.399 90)
			(layer "B.Fab")
			(effects
				(font
					(size 0.7 0.7)
					(thickness 0.15)
				)
				(justify right top mirror)
			)
		)
		(fp_text user "${REFERENCE}"
			(at -0.939 -4.599 90)
			(layer "B.Fab")
			(effects
				(font
					(size 0.7 0.7)
					(thickness 0.15)
				)
				(justify right top mirror)
			)
		)
		(pad "1" smd roundrect
			(at -0.48 0 90)
			(size 0.59 0.64)
			(layers "B.Cu" "B.Mask" "B.Paste")
			(roundrect_rratio 0.25)
			(net 1 "GND")
			(pintype "passive")
		)
		(pad "2" smd roundrect
			(at 0.48 0 90)
			(size 0.59 0.64)
			(layers "B.Cu" "B.Mask" "B.Paste")
			(roundrect_rratio 0.25)
			(net 488 "/USB Debug, PD/USBC0_D_N")
			(pintype "passive")
		)
	)
	(footprint "antmicro-footprints:TP_SMD_0.75mm"
		(layer "B.Cu")
		(at 89.96 76.59 90)
		(property "Reference" "TP58"
			(at 0.39 0.64 180)
			(layer "B.SilkS")
			(effects
				(font
					(size 0.7 0.7)
					(thickness 0.15)
				)
				(justify right top mirror)
			)
		)
		(property "Value" "TP_0.75mm_SMD"
			(at 0 -1.2 90)
			(layer "B.Fab")
			(effects
				(font
					(size 0.7 0.7)
					(thickness 0.15)
				)
				(justify right top mirror)
			)
		)
		(property "Description" "SMT test point"
			(at 0 0 90)
			(layer "B.Fab")
			(hide yes)
			(effects
				(font
					(size 1.27 1.27)
					(thickness 0.15)
				)
				(justify mirror)
			)
		)
		(property "MPN" ""
			(at 0 0 270)
			(unlocked yes)
			(layer "B.Fab")
			(hide yes)
			(effects
				(font
					(size 1 1)
					(thickness 0.15)
				)
				(justify mirror)
			)
		)
		(property "Manufacturer" ""
			(at 0 0 270)
			(unlocked yes)
			(layer "B.Fab")
			(hide yes)
			(effects
				(font
					(size 1 1)
					(thickness 0.15)
				)
				(justify mirror)
			)
		)
		(property "Author" "Antmicro"
			(at 0 0 270)
			(unlocked yes)
			(layer "B.Fab")
			(hide yes)
			(effects
				(font
					(size 1 1)
					(thickness 0.15)
				)
				(justify mirror)
			)
		)
		(property "License" "Apache-2.0"
			(at 0 0 270)
			(unlocked yes)
			(layer "B.Fab")
			(hide yes)
			(effects
				(font
					(size 1 1)
					(thickness 0.15)
				)
				(justify mirror)
			)
		)
		(sheetname "/SoM_Power/")
		(sheetfile "som_power.kicad_sch")
		(attr exclude_from_pos_files exclude_from_bom)
		(fp_circle
			(center 0 0)
			(end 0.475 0)
			(stroke
				(width 0.05)
				(type default)
			)
			(fill no)
			(layer "B.CrtYd")
		)
		(fp_text user "Author: Antmicro"
			(at -0.4 -3.901 90)
			(layer "B.Fab")
			(effects
				(font
					(size 0.7 0.7)
					(thickness 0.15)
				)
				(justify right top mirror)
			)
		)
		(fp_text user "${REFERENCE}"
			(at -0.4 -2.7 90)
			(layer "B.Fab")
			(effects
				(font
					(size 0.7 0.7)
					(thickness 0.15)
				)
				(justify right top mirror)
			)
		)
		(fp_text user "License: Apache-2.0"
			(at -0.4 -5.101 90)
			(layer "B.Fab")
			(effects
				(font
					(size 0.7 0.7)
					(thickness 0.15)
				)
				(justify right top mirror)
			)
		)
		(pad "1" smd circle
			(at 0 0 90)
			(size 0.75 0.75)
			(layers "B.Cu" "B.Mask")
			(net 739 "Net-(J1A-GPIO56)")
			(pinfunction "1")
			(pintype "passive")
		)
	)
)
